#ISCELL
  mstr_misc prelim *
  *
#ISCELL
  mstr_symbols design_note *
  *
#ISCELL
  mstr_symbols intel_corp_bpage *
  *
#ISCELL
  mstr_symbols gnd *
  page74_i1
#ISCELL
  mstr_symbols gnd *
  page74_i11
#ISCELL
  mstr_symbols gnd *
  page74_i12
#ISCELL
  mstr_symbols gnd *
  page74_i14
#CELL
  chpset_lib skx_ext_b *
  page74_i20
#CELL
  chpset_lib skx_ext_b *
  page74_i21
#CELL
  chpset_lib skx_ext_b *
  page74_i22
#CELL
  chpset_lib skx_ext_b *
  page74_i23
#ISCELL
  mstr_symbols gnd *
  page74_i3
#ISCELL
  mstr_symbols gnd *
  page74_i4
#ISCELL
  mstr_symbols gnd *
  page74_i6
#ISCELL
  mstr_symbols gnd *
  page74_i9
